(kicad_pcb
	(version 20260206)
	(generator "pcbnew")
	(generator_version "10.0")
	(general
		(thickness 1.6)
		(legacy_teardrops no)
	)
	(paper "A4")
	(title_block
		(title "peb — Lightning_PEB_BRD.brd")
		(comment 1 "Lightning (Wiwynn / Facebook NVMe JBOF) / footprints 1117-1124 of 2563")
	)
	(layers
		(0 "F.Cu" signal "TOP")
		(4 "In1.Cu" signal "L2GND")
		(6 "In2.Cu" signal "L3")
		(8 "In3.Cu" signal "L4VCC")
		(10 "In4.Cu" signal "L5VCC")
		(12 "In5.Cu" signal "L6")
		(14 "In6.Cu" signal "L7GND")
		(2 "B.Cu" signal "BOTTOM")
		(9 "F.Adhes" user "F.Adhesive")
		(11 "B.Adhes" user "B.Adhesive")
		(13 "F.Paste" user "Package Geometry/Pastemask Top")
		(15 "B.Paste" user "Package Geometry/Pastemask Bottom")
		(5 "F.SilkS" user "Ref Des/Silkscreen Top")
		(7 "B.SilkS" user "Ref Des/Silkscreen Bottom")
		(1 "F.Mask" user "Board Geometry/Soldermask Top")
		(3 "B.Mask" user "Board Geometry/Soldermask Bottom")
		(17 "Dwgs.User" user "User.Drawings")
		(19 "Cmts.User" user "User.Comments")
		(21 "Eco1.User" user "User.Eco1")
		(23 "Eco2.User" user "User.Eco2")
		(25 "Edge.Cuts" user "Board Geometry/Outline")
		(27 "Margin" user)
		(31 "F.CrtYd" user "Package Geometry/Place Bound Top")
		(29 "B.CrtYd" user "Package Geometry/Place Bound Bottom")
		(35 "F.Fab" user "Ref Des/Assembly Top")
		(33 "B.Fab" user "Ref Des/Assembly Bottom")
	)
	(footprint ""
		(layer "F.Cu")
		(at 23.876 -134.747 90)
		(property "Reference" "R354"
			(at 0 0 90)
			(layer "F.SilkS")
			(hide yes)
			(effects
				(font
					(size 1.27 1.27)
				)
			)
		)
		(property "Value" "3K3R2F-2-GP"
			(at 0.064008 -3.993896 90)
			(unlocked yes)
			(layer "F.Fab")
			(hide yes)
			(effects
				(font
					(size 1.016 1.016)
					(thickness 0.1524)
				)
			)
		)
		(property "Device Type" "R402H16"
			(at 0.064008 -5.517896 90)
			(unlocked yes)
			(layer "F.Fab")
			(hide yes)
			(effects
				(font
					(size 1.016 1.016)
					(thickness 0.1524)
				)
			)
		)
		(duplicate_pad_numbers_are_jumpers no)
		(fp_line
			(start 0.508 -0.9398)
			(end -0.508 -0.9398)
			(stroke
				(width 0.1524)
				(type default)
			)
			(layer "F.SilkS")
		)
		(fp_line
			(start -0.508 -0.9398)
			(end -0.508 0.9398)
			(stroke
				(width 0.1524)
				(type default)
			)
			(layer "F.SilkS")
		)
		(fp_rect
			(start -0.508 0.9398)
			(end 0.508 -0.9398)
			(stroke
				(width 0)
				(type default)
			)
			(fill no)
			(layer "F.CrtYd")
		)
		(fp_rect
			(start -0.508 0.9398)
			(end 0.508 -0.9398)
			(stroke
				(width 0)
				(type default)
			)
			(fill no)
			(layer "F.Fab")
		)
		(pad "1" smd custom
			(at 0 -0.4445 90)
			(size 0.1397 0.1397)
			(layers "F.Cu" "F.Mask" "F.Paste")
			(net "P3V3_STBY")
			(options
				(clearance outline)
				(anchor circle)
			)
			(primitives
				(gr_poly
					(pts
						(arc
							(start -0.1778 -0.2794)
							(mid -0.249642 -0.249642)
							(end -0.2794 -0.1778)
						)
						(arc
							(start -0.2794 0.1778)
							(mid -0.249642 0.249642)
							(end -0.1778 0.2794)
						)
						(arc
							(start 0.1778 0.2794)
							(mid 0.249642 0.249642)
							(end 0.2794 0.1778)
						)
						(arc
							(start 0.2794 -0.1778)
							(mid 0.249642 -0.249642)
							(end 0.1778 -0.2794)
						)
					)
					(width 0)
					(fill yes)
				)
			)
		)
		(pad "2" smd custom
			(at 0 0.4445 90)
			(size 0.1397 0.1397)
			(layers "F.Cu" "F.Mask" "F.Paste")
			(net "ROMD3")
			(options
				(clearance outline)
				(anchor circle)
			)
			(primitives
				(gr_poly
					(pts
						(arc
							(start -0.1778 -0.2794)
							(mid -0.249642 -0.249642)
							(end -0.2794 -0.1778)
						)
						(arc
							(start -0.2794 0.1778)
							(mid -0.249642 0.249642)
							(end -0.1778 0.2794)
						)
						(arc
							(start 0.1778 0.2794)
							(mid 0.249642 0.249642)
							(end 0.2794 0.1778)
						)
						(arc
							(start 0.2794 -0.1778)
							(mid 0.249642 -0.249642)
							(end 0.1778 -0.2794)
						)
					)
					(width 0)
					(fill yes)
				)
			)
		)
	)
	(footprint ""
		(layer "F.Cu")
		(at 284.988 -59.69 -90)
		(property "Reference" "R609"
			(at 0 0 270)
			(layer "F.SilkS")
			(hide yes)
			(effects
				(font
					(size 1.27 1.27)
				)
			)
		)
		(property "Value" "0R2J-2-GP"
			(at 0.064008 -3.993896 270)
			(unlocked yes)
			(layer "F.Fab")
			(hide yes)
			(effects
				(font
					(size 1.016 1.016)
					(thickness 0.1524)
				)
			)
		)
		(property "Device Type" "R402H16"
			(at 0.064008 -5.517896 270)
			(unlocked yes)
			(layer "F.Fab")
			(hide yes)
			(effects
				(font
					(size 1.016 1.016)
					(thickness 0.1524)
				)
			)
		)
		(duplicate_pad_numbers_are_jumpers no)
		(fp_line
			(start -0.508 -0.9398)
			(end -0.508 0.9398)
			(stroke
				(width 0.1524)
				(type default)
			)
			(layer "F.SilkS")
		)
		(fp_line
			(start 0.508 -0.9398)
			(end -0.508 -0.9398)
			(stroke
				(width 0.1524)
				(type default)
			)
			(layer "F.SilkS")
		)
		(fp_rect
			(start -0.508 0.9398)
			(end 0.508 -0.9398)
			(stroke
				(width 0)
				(type default)
			)
			(fill no)
			(layer "F.CrtYd")
		)
		(fp_rect
			(start -0.508 0.9398)
			(end 0.508 -0.9398)
			(stroke
				(width 0)
				(type default)
			)
			(fill no)
			(layer "F.Fab")
		)
		(pad "1" smd custom
			(at 0 -0.4445 270)
			(size 0.1397 0.1397)
			(layers "F.Cu" "F.Mask" "F.Paste")
			(net "VS4_LED_R")
			(options
				(clearance outline)
				(anchor circle)
			)
			(primitives
				(gr_poly
					(pts
						(arc
							(start -0.1778 -0.2794)
							(mid -0.249642 -0.249642)
							(end -0.2794 -0.1778)
						)
						(arc
							(start -0.2794 0.1778)
							(mid -0.249642 0.249642)
							(end -0.1778 0.2794)
						)
						(arc
							(start 0.1778 0.2794)
							(mid 0.249642 0.249642)
							(end 0.2794 0.1778)
						)
						(arc
							(start 0.2794 -0.1778)
							(mid 0.249642 -0.249642)
							(end 0.1778 -0.2794)
						)
					)
					(width 0)
					(fill yes)
				)
			)
		)
		(pad "2" smd custom
			(at 0 0.4445 270)
			(size 0.1397 0.1397)
			(layers "F.Cu" "F.Mask" "F.Paste")
			(net "VS4_LED")
			(options
				(clearance outline)
				(anchor circle)
			)
			(primitives
				(gr_poly
					(pts
						(arc
							(start -0.1778 -0.2794)
							(mid -0.249642 -0.249642)
							(end -0.2794 -0.1778)
						)
						(arc
							(start -0.2794 0.1778)
							(mid -0.249642 0.249642)
							(end -0.1778 0.2794)
						)
						(arc
							(start 0.1778 0.2794)
							(mid 0.249642 0.249642)
							(end 0.2794 0.1778)
						)
						(arc
							(start 0.2794 -0.1778)
							(mid 0.249642 -0.249642)
							(end 0.1778 -0.2794)
						)
					)
					(width 0)
					(fill yes)
				)
			)
		)
	)
	(footprint ""
		(layer "F.Cu")
		(at 296.672 -68.834 180)
		(property "Reference" "C454"
			(at 0 0 180)
			(layer "F.SilkS")
			(hide yes)
			(effects
				(font
					(size 1.27 1.27)
				)
			)
		)
		(property "Value" "SC100U4V5MX-1-GP"
			(at -0.0762 -6.1214 180)
			(unlocked yes)
			(layer "F.Fab")
			(hide yes)
			(effects
				(font
					(size 1.016 1.016)
					(thickness 0.1524)
				)
			)
		)
		(property "Device Type" "C805H58"
			(at -0.0762 -8.1534 180)
			(unlocked yes)
			(layer "F.Fab")
			(hide yes)
			(effects
				(font
					(size 1.016 1.016)
					(thickness 0.1524)
				)
			)
		)
		(duplicate_pad_numbers_are_jumpers no)
		(fp_line
			(start 0.635 0)
			(end -0.635 0)
			(stroke
				(width 0.508)
				(type default)
			)
			(layer "F.SilkS")
		)
		(fp_rect
			(start -0.9652 1.778)
			(end 0.9652 -1.778)
			(stroke
				(width 0)
				(type default)
			)
			(fill no)
			(layer "F.CrtYd")
		)
		(fp_poly
			(pts
				(xy -0.9652 -1.778) (xy 0.9652 -1.778) (xy 0.9652 1.778) (xy -0.9652 1.778)
			)
			(stroke
				(width 0)
				(type default)
			)
			(fill no)
			(layer "F.Fab")
		)
		(pad "1" smd rect
			(at 0 -0.9652 180)
			(size 1.397 1.143)
			(layers "F.Cu" "F.Mask" "F.Paste")
			(net "DUT_VDD")
		)
		(pad "2" smd rect
			(at 0 0.9652 180)
			(size 1.397 1.143)
			(layers "F.Cu" "F.Mask" "F.Paste")
			(net "GND")
		)
	)
	(footprint ""
		(layer "F.Cu")
		(at 43.8912 -116.713)
		(property "Reference" "R473"
			(at 0 0 0)
			(layer "F.SilkS")
			(hide yes)
			(effects
				(font
					(size 1.27 1.27)
				)
			)
		)
		(property "Value" "0R2J-2-GP"
			(at 0.064008 -3.993896 0)
			(unlocked yes)
			(layer "F.Fab")
			(hide yes)
			(effects
				(font
					(size 1.016 1.016)
					(thickness 0.1524)
				)
			)
		)
		(property "Device Type" "R402H16"
			(at 0.064008 -5.517896 0)
			(unlocked yes)
			(layer "F.Fab")
			(hide yes)
			(effects
				(font
					(size 1.016 1.016)
					(thickness 0.1524)
				)
			)
		)
		(duplicate_pad_numbers_are_jumpers no)
		(fp_line
			(start -0.508 -0.9398)
			(end -0.508 0.9398)
			(stroke
				(width 0.1524)
				(type default)
			)
			(layer "F.SilkS")
		)
		(fp_line
			(start 0.508 -0.9398)
			(end -0.508 -0.9398)
			(stroke
				(width 0.1524)
				(type default)
			)
			(layer "F.SilkS")
		)
		(fp_rect
			(start -0.508 0.9398)
			(end 0.508 -0.9398)
			(stroke
				(width 0)
				(type default)
			)
			(fill no)
			(layer "F.CrtYd")
		)
		(fp_rect
			(start -0.508 0.9398)
			(end 0.508 -0.9398)
			(stroke
				(width 0)
				(type default)
			)
			(fill no)
			(layer "F.Fab")
		)
		(pad "1" smd custom
			(at 0 -0.4445)
			(size 0.1397 0.1397)
			(layers "F.Cu" "F.Mask" "F.Paste")
			(net "GPIOH2_R")
			(options
				(clearance outline)
				(anchor circle)
			)
			(primitives
				(gr_poly
					(pts
						(arc
							(start -0.1778 -0.2794)
							(mid -0.249642 -0.249642)
							(end -0.2794 -0.1778)
						)
						(arc
							(start -0.2794 0.1778)
							(mid -0.249642 0.249642)
							(end -0.1778 0.2794)
						)
						(arc
							(start 0.1778 0.2794)
							(mid 0.249642 0.249642)
							(end 0.2794 0.1778)
						)
						(arc
							(start 0.2794 -0.1778)
							(mid 0.249642 -0.249642)
							(end 0.1778 -0.2794)
						)
					)
					(width 0)
					(fill yes)
				)
			)
		)
		(pad "2" smd custom
			(at 0 0.4445)
			(size 0.1397 0.1397)
			(layers "F.Cu" "F.Mask" "F.Paste")
			(net "GPIOH2")
			(options
				(clearance outline)
				(anchor circle)
			)
			(primitives
				(gr_poly
					(pts
						(arc
							(start -0.1778 -0.2794)
							(mid -0.249642 -0.249642)
							(end -0.2794 -0.1778)
						)
						(arc
							(start -0.2794 0.1778)
							(mid -0.249642 0.249642)
							(end -0.1778 0.2794)
						)
						(arc
							(start 0.1778 0.2794)
							(mid 0.249642 0.249642)
							(end 0.2794 0.1778)
						)
						(arc
							(start 0.2794 -0.1778)
							(mid 0.249642 -0.249642)
							(end 0.1778 -0.2794)
						)
					)
					(width 0)
					(fill yes)
				)
			)
		)
	)
	(footprint ""
		(layer "F.Cu")
		(at 6.8072 -185.2676 -90)
		(property "Reference" "PR9004"
			(at 0 0 270)
			(layer "F.SilkS")
			(hide yes)
			(effects
				(font
					(size 1.27 1.27)
				)
			)
		)
		(property "Value" "0R2J-2-GP"
			(at 0.064008 -3.993896 270)
			(unlocked yes)
			(layer "F.Fab")
			(hide yes)
			(effects
				(font
					(size 1.016 1.016)
					(thickness 0.1524)
				)
			)
		)
		(property "Device Type" "R402H16"
			(at 0.064008 -5.517896 270)
			(unlocked yes)
			(layer "F.Fab")
			(hide yes)
			(effects
				(font
					(size 1.016 1.016)
					(thickness 0.1524)
				)
			)
		)
		(duplicate_pad_numbers_are_jumpers no)
		(fp_line
			(start -0.508 -0.9398)
			(end -0.508 0.9398)
			(stroke
				(width 0.1524)
				(type default)
			)
			(layer "F.SilkS")
		)
		(fp_line
			(start 0.508 -0.9398)
			(end -0.508 -0.9398)
			(stroke
				(width 0.1524)
				(type default)
			)
			(layer "F.SilkS")
		)
		(fp_rect
			(start -0.508 0.9398)
			(end 0.508 -0.9398)
			(stroke
				(width 0)
				(type default)
			)
			(fill no)
			(layer "F.CrtYd")
		)
		(fp_rect
			(start -0.508 0.9398)
			(end 0.508 -0.9398)
			(stroke
				(width 0)
				(type default)
			)
			(fill no)
			(layer "F.Fab")
		)
		(pad "1" smd custom
			(at 0 -0.4445 270)
			(size 0.1397 0.1397)
			(layers "F.Cu" "F.Mask" "F.Paste")
			(net "HSW_SCL_2")
			(options
				(clearance outline)
				(anchor circle)
			)
			(primitives
				(gr_poly
					(pts
						(arc
							(start -0.1778 -0.2794)
							(mid -0.249642 -0.249642)
							(end -0.2794 -0.1778)
						)
						(arc
							(start -0.2794 0.1778)
							(mid -0.249642 0.249642)
							(end -0.1778 0.2794)
						)
						(arc
							(start 0.1778 0.2794)
							(mid 0.249642 0.249642)
							(end 0.2794 0.1778)
						)
						(arc
							(start 0.2794 -0.1778)
							(mid 0.249642 -0.249642)
							(end 0.1778 -0.2794)
						)
					)
					(width 0)
					(fill yes)
				)
			)
		)
		(pad "2" smd custom
			(at 0 0.4445 270)
			(size 0.1397 0.1397)
			(layers "F.Cu" "F.Mask" "F.Paste")
			(net "BMC_I2C5_D_PEB_SCL")
			(options
				(clearance outline)
				(anchor circle)
			)
			(primitives
				(gr_poly
					(pts
						(arc
							(start -0.1778 -0.2794)
							(mid -0.249642 -0.249642)
							(end -0.2794 -0.1778)
						)
						(arc
							(start -0.2794 0.1778)
							(mid -0.249642 0.249642)
							(end -0.1778 0.2794)
						)
						(arc
							(start 0.1778 0.2794)
							(mid 0.249642 0.249642)
							(end 0.2794 0.1778)
						)
						(arc
							(start 0.2794 -0.1778)
							(mid 0.249642 -0.249642)
							(end 0.1778 -0.2794)
						)
					)
					(width 0)
					(fill yes)
				)
			)
		)
	)
	(footprint ""
		(layer "F.Cu")
		(at 18.3642 -66.9798)
		(property "Reference" "C637"
			(at 0 0 0)
			(layer "F.SilkS")
			(hide yes)
			(effects
				(font
					(size 1.27 1.27)
				)
			)
		)
		(property "Value" "SCD1U16V2KX-3GP"
			(at 1.1811 -2.7051 0)
			(unlocked yes)
			(layer "F.Fab")
			(hide yes)
			(effects
				(font
					(size 1.016 1.016)
					(thickness 0.1524)
				)
			)
		)
		(property "Device Type" "C402H22"
			(at 1.1811 -4.2291 0)
			(unlocked yes)
			(layer "F.Fab")
			(hide yes)
			(effects
				(font
					(size 1.016 1.016)
					(thickness 0.1524)
				)
			)
		)
		(duplicate_pad_numbers_are_jumpers no)
		(fp_rect
			(start -0.4318 0.9525)
			(end 0.4318 -0.9525)
			(stroke
				(width 0)
				(type default)
			)
			(fill no)
			(layer "F.CrtYd")
		)
		(fp_rect
			(start -0.4318 0.9525)
			(end 0.4318 -0.9525)
			(stroke
				(width 0)
				(type default)
			)
			(fill no)
			(layer "F.Fab")
		)
		(pad "1" smd custom
			(at 0 -0.4445)
			(size 0.1524 0.1524)
			(layers "F.Cu" "F.Mask" "F.Paste")
			(net "P0V9_I210")
			(options
				(clearance outline)
				(anchor circle)
			)
			(primitives
				(gr_poly
					(pts
						(arc
							(start 0.3048 -0.2032)
							(mid 0.275042 -0.275042)
							(end 0.2032 -0.3048)
						)
						(arc
							(start -0.2032 -0.3048)
							(mid -0.275042 -0.275042)
							(end -0.3048 -0.2032)
						)
						(arc
							(start -0.3048 0.2032)
							(mid -0.275042 0.275042)
							(end -0.2032 0.3048)
						)
						(arc
							(start 0.2032 0.3048)
							(mid 0.275042 0.275042)
							(end 0.3048 0.2032)
						)
					)
					(width 0)
					(fill yes)
				)
			)
		)
		(pad "2" smd custom
			(at 0 0.4445)
			(size 0.1524 0.1524)
			(layers "F.Cu" "F.Mask" "F.Paste")
			(net "GND")
			(options
				(clearance outline)
				(anchor circle)
			)
			(primitives
				(gr_poly
					(pts
						(arc
							(start 0.3048 -0.2032)
							(mid 0.275042 -0.275042)
							(end 0.2032 -0.3048)
						)
						(arc
							(start -0.2032 -0.3048)
							(mid -0.275042 -0.275042)
							(end -0.3048 -0.2032)
						)
						(arc
							(start -0.3048 0.2032)
							(mid -0.275042 0.275042)
							(end -0.2032 0.3048)
						)
						(arc
							(start 0.2032 0.3048)
							(mid 0.275042 0.275042)
							(end 0.3048 0.2032)
						)
					)
					(width 0)
					(fill yes)
				)
			)
		)
	)
	(footprint ""
		(layer "F.Cu")
		(at 218.9988 -0.9906 90)
		(property "Reference" "R412"
			(at 0 0 90)
			(layer "F.SilkS")
			(hide yes)
			(effects
				(font
					(size 1.27 1.27)
				)
			)
		)
		(property "Value" "0R2J-2-GP"
			(at 0.064008 -3.993896 90)
			(unlocked yes)
			(layer "F.Fab")
			(hide yes)
			(effects
				(font
					(size 1.016 1.016)
					(thickness 0.1524)
				)
			)
		)
		(property "Device Type" "R402H16"
			(at 0.064008 -5.517896 90)
			(unlocked yes)
			(layer "F.Fab")
			(hide yes)
			(effects
				(font
					(size 1.016 1.016)
					(thickness 0.1524)
				)
			)
		)
		(duplicate_pad_numbers_are_jumpers no)
		(fp_line
			(start 0.508 -0.9398)
			(end -0.508 -0.9398)
			(stroke
				(width 0.1524)
				(type default)
			)
			(layer "F.SilkS")
		)
		(fp_line
			(start -0.508 -0.9398)
			(end -0.508 0.9398)
			(stroke
				(width 0.1524)
				(type default)
			)
			(layer "F.SilkS")
		)
		(fp_rect
			(start -0.508 0.9398)
			(end 0.508 -0.9398)
			(stroke
				(width 0)
				(type default)
			)
			(fill no)
			(layer "F.CrtYd")
		)
		(fp_rect
			(start -0.508 0.9398)
			(end 0.508 -0.9398)
			(stroke
				(width 0)
				(type default)
			)
			(fill no)
			(layer "F.Fab")
		)
		(pad "1" smd custom
			(at 0 -0.4445 90)
			(size 0.1397 0.1397)
			(layers "F.Cu" "F.Mask" "F.Paste")
			(net "EXP_SMART_RX")
			(options
				(clearance outline)
				(anchor circle)
			)
			(primitives
				(gr_poly
					(pts
						(arc
							(start -0.1778 -0.2794)
							(mid -0.249642 -0.249642)
							(end -0.2794 -0.1778)
						)
						(arc
							(start -0.2794 0.1778)
							(mid -0.249642 0.249642)
							(end -0.1778 0.2794)
						)
						(arc
							(start 0.1778 0.2794)
							(mid 0.249642 0.249642)
							(end 0.2794 0.1778)
						)
						(arc
							(start 0.2794 -0.1778)
							(mid 0.249642 -0.249642)
							(end 0.1778 -0.2794)
						)
					)
					(width 0)
					(fill yes)
				)
			)
		)
		(pad "2" smd custom
			(at 0 0.4445 90)
			(size 0.1397 0.1397)
			(layers "F.Cu" "F.Mask" "F.Paste")
			(net "EXP_UART_RX_R")
			(options
				(clearance outline)
				(anchor circle)
			)
			(primitives
				(gr_poly
					(pts
						(arc
							(start -0.1778 -0.2794)
							(mid -0.249642 -0.249642)
							(end -0.2794 -0.1778)
						)
						(arc
							(start -0.2794 0.1778)
							(mid -0.249642 0.249642)
							(end -0.1778 0.2794)
						)
						(arc
							(start 0.1778 0.2794)
							(mid 0.249642 0.249642)
							(end 0.2794 0.1778)
						)
						(arc
							(start 0.2794 -0.1778)
							(mid 0.249642 -0.249642)
							(end 0.1778 -0.2794)
						)
					)
					(width 0)
					(fill yes)
				)
			)
		)
	)
	(footprint ""
		(layer "F.Cu")
		(at 331.756512 -184.878218)
		(property "Reference" "R7966"
			(at 0 0 0)
			(layer "F.SilkS")
			(hide yes)
			(effects
				(font
					(size 1.27 1.27)
				)
			)
		)
		(property "Value" "0R2J-2-GP"
			(at 0.064008 -3.993896 0)
			(unlocked yes)
			(layer "F.Fab")
			(hide yes)
			(effects
				(font
					(size 1.016 1.016)
					(thickness 0.1524)
				)
			)
		)
		(property "Device Type" "R402H16"
			(at 0.064008 -5.517896 0)
			(unlocked yes)
			(layer "F.Fab")
			(hide yes)
			(effects
				(font
					(size 1.016 1.016)
					(thickness 0.1524)
				)
			)
		)
		(duplicate_pad_numbers_are_jumpers no)
		(fp_line
			(start -0.508 -0.9398)
			(end -0.508 0.9398)
			(stroke
				(width 0.1524)
				(type default)
			)
			(layer "F.SilkS")
		)
		(fp_line
			(start 0.508 -0.9398)
			(end -0.508 -0.9398)
			(stroke
				(width 0.1524)
				(type default)
			)
			(layer "F.SilkS")
		)
		(fp_rect
			(start -0.508 0.9398)
			(end 0.508 -0.9398)
			(stroke
				(width 0)
				(type default)
			)
			(fill no)
			(layer "F.CrtYd")
		)
		(fp_rect
			(start -0.508 0.9398)
			(end 0.508 -0.9398)
			(stroke
				(width 0)
				(type default)
			)
			(fill no)
			(layer "F.Fab")
		)
		(pad "1" smd custom
			(at 0 -0.4445)
			(size 0.1397 0.1397)
			(layers "F.Cu" "F.Mask" "F.Paste")
			(net "TWI_SCL1")
			(options
				(clearance outline)
				(anchor circle)
			)
			(primitives
				(gr_poly
					(pts
						(arc
							(start -0.1778 -0.2794)
							(mid -0.249642 -0.249642)
							(end -0.2794 -0.1778)
						)
						(arc
							(start -0.2794 0.1778)
							(mid -0.249642 0.249642)
							(end -0.1778 0.2794)
						)
						(arc
							(start 0.1778 0.2794)
							(mid 0.249642 0.249642)
							(end 0.2794 0.1778)
						)
						(arc
							(start 0.2794 -0.1778)
							(mid 0.249642 -0.249642)
							(end 0.1778 -0.2794)
						)
					)
					(width 0)
					(fill yes)
				)
			)
		)
		(pad "2" smd custom
			(at 0 0.4445)
			(size 0.1397 0.1397)
			(layers "F.Cu" "F.Mask" "F.Paste")
			(net "I2C_GPIO_SCL_4")
			(options
				(clearance outline)
				(anchor circle)
			)
			(primitives
				(gr_poly
					(pts
						(arc
							(start -0.1778 -0.2794)
							(mid -0.249642 -0.249642)
							(end -0.2794 -0.1778)
						)
						(arc
							(start -0.2794 0.1778)
							(mid -0.249642 0.249642)
							(end -0.1778 0.2794)
						)
						(arc
							(start 0.1778 0.2794)
							(mid 0.249642 0.249642)
							(end 0.2794 0.1778)
						)
						(arc
							(start 0.2794 -0.1778)
							(mid 0.249642 -0.249642)
							(end 0.1778 -0.2794)
						)
					)
					(width 0)
					(fill yes)
				)
			)
		)
	)
)
